(kicad_pcb
	(version 20260206)
	(generator "pcbnew")
	(generator_version "10.0")
	(general
		(thickness 1.6)
		(legacy_teardrops no)
	)
	(paper "A4")
	(title_block
		(title "Bryce Canyon_IOM_M2_16342-2_OCP.brd")
		(comment 1 "Bryce Canyon / footprints 1074-1081 of 1146")
	)
	(layers
		(0 "F.Cu" signal "TOP")
		(4 "In1.Cu" signal "L2GND")
		(6 "In2.Cu" signal "L3")
		(8 "In3.Cu" signal "L4VCC")
		(10 "In4.Cu" signal "L5VCC")
		(12 "In5.Cu" signal "L6")
		(14 "In6.Cu" signal "L7GND")
		(2 "B.Cu" signal "BOTTOM")
		(9 "F.Adhes" user "F.Adhesive")
		(11 "B.Adhes" user "B.Adhesive")
		(13 "F.Paste" user "Package Geometry/Pastemask Top")
		(15 "B.Paste" user "Package Geometry/Pastemask Bottom")
		(5 "F.SilkS" user "Ref Des/Silkscreen Top")
		(7 "B.SilkS" user "Ref Des/Silkscreen Bottom")
		(1 "F.Mask" user "Board Geometry/Soldermask Top")
		(3 "B.Mask" user "Board Geometry/Soldermask Bottom")
		(17 "Dwgs.User" user "User.Drawings")
		(19 "Cmts.User" user "User.Comments")
		(21 "Eco1.User" user "User.Eco1")
		(23 "Eco2.User" user "User.Eco2")
		(25 "Edge.Cuts" user "Board Geometry/Outline")
		(27 "Margin" user)
		(31 "F.CrtYd" user "Package Geometry/Place Bound Top")
		(29 "B.CrtYd" user "Package Geometry/Place Bound Bottom")
		(35 "F.Fab" user "Ref Des/Assembly Top")
		(33 "B.Fab" user "Ref Des/Assembly Bottom")
	)
	(footprint ""
		(layer "B.Cu")
		(at 43.9928 -134.7978 90)
		(property "Reference" "R372"
			(at 0 0 90)
			(layer "B.SilkS")
			(hide yes)
			(effects
				(font
					(size 1.27 1.27)
				)
				(justify mirror)
			)
		)
		(property "Value" "4K7R2F-GP"
			(at -0.064008 -3.993896 90)
			(unlocked yes)
			(layer "B.Fab")
			(hide yes)
			(effects
				(font
					(size 1.016 1.016)
					(thickness 0.1524)
				)
				(justify mirror)
			)
		)
		(property "Device Type" "R402H16"
			(at -0.064008 -5.517896 90)
			(unlocked yes)
			(layer "B.Fab")
			(hide yes)
			(effects
				(font
					(size 1.016 1.016)
					(thickness 0.1524)
				)
				(justify mirror)
			)
		)
		(duplicate_pad_numbers_are_jumpers no)
		(fp_line
			(start 0.508 -0.9398)
			(end 0.508 0.9398)
			(stroke
				(width 0.1524)
				(type default)
			)
			(layer "B.SilkS")
		)
		(fp_line
			(start -0.508 -0.9398)
			(end 0.508 -0.9398)
			(stroke
				(width 0.1524)
				(type default)
			)
			(layer "B.SilkS")
		)
		(fp_rect
			(start 0.508 0.9398)
			(end -0.508 -0.9398)
			(stroke
				(width 0)
				(type default)
			)
			(fill no)
			(layer "B.CrtYd")
		)
		(fp_rect
			(start 0.508 0.9398)
			(end -0.508 -0.9398)
			(stroke
				(width 0)
				(type default)
			)
			(fill no)
			(layer "B.Fab")
		)
		(pad "1" smd custom
			(at 0 -0.4445 270)
			(size 0.1397 0.1397)
			(layers "B.Cu" "B.Mask" "B.Paste")
			(net "P3V3_STBY")
			(options
				(clearance outline)
				(anchor circle)
			)
			(primitives
				(gr_poly
					(pts
						(arc
							(start -0.1778 0.2794)
							(mid -0.249642 0.249642)
							(end -0.2794 0.1778)
						)
						(arc
							(start -0.2794 -0.1778)
							(mid -0.249642 -0.249642)
							(end -0.1778 -0.2794)
						)
						(arc
							(start 0.1778 -0.2794)
							(mid 0.249642 -0.249642)
							(end 0.2794 -0.1778)
						)
						(arc
							(start 0.2794 0.1778)
							(mid 0.249642 0.249642)
							(end 0.1778 0.2794)
						)
					)
					(width 0)
					(fill yes)
				)
			)
		)
		(pad "2" smd custom
			(at 0 0.4445 270)
			(size 0.1397 0.1397)
			(layers "B.Cu" "B.Mask" "B.Paste")
			(net "BMC_GPIOS4")
			(options
				(clearance outline)
				(anchor circle)
			)
			(primitives
				(gr_poly
					(pts
						(arc
							(start -0.1778 0.2794)
							(mid -0.249642 0.249642)
							(end -0.2794 0.1778)
						)
						(arc
							(start -0.2794 -0.1778)
							(mid -0.249642 -0.249642)
							(end -0.1778 -0.2794)
						)
						(arc
							(start 0.1778 -0.2794)
							(mid 0.249642 -0.249642)
							(end 0.2794 -0.1778)
						)
						(arc
							(start 0.2794 0.1778)
							(mid 0.249642 0.249642)
							(end 0.1778 0.2794)
						)
					)
					(width 0)
					(fill yes)
				)
			)
		)
	)
	(footprint ""
		(layer "B.Cu")
		(at 197.926706 -133.61924 180)
		(property "Reference" "C625"
			(at 0 0 0)
			(layer "B.SilkS")
			(hide yes)
			(effects
				(font
					(size 1.27 1.27)
				)
				(justify mirror)
			)
		)
		(property "Value" "SC10U6D3V5KX-4GP"
			(at 0.0762 -6.1214 180)
			(unlocked yes)
			(layer "B.Fab")
			(hide yes)
			(effects
				(font
					(size 1.016 1.016)
					(thickness 0.1524)
				)
				(justify mirror)
			)
		)
		(property "Device Type" "C805H58"
			(at 0.0762 -8.1534 180)
			(unlocked yes)
			(layer "B.Fab")
			(hide yes)
			(effects
				(font
					(size 1.016 1.016)
					(thickness 0.1524)
				)
				(justify mirror)
			)
		)
		(duplicate_pad_numbers_are_jumpers no)
		(fp_line
			(start -0.635 0)
			(end 0.635 0)
			(stroke
				(width 0.508)
				(type default)
			)
			(layer "B.SilkS")
		)
		(fp_rect
			(start 0.9652 1.778)
			(end -0.9652 -1.778)
			(stroke
				(width 0)
				(type default)
			)
			(fill no)
			(layer "B.CrtYd")
		)
		(fp_poly
			(pts
				(xy 0.9652 -1.778) (xy -0.9652 -1.778) (xy -0.9652 1.778) (xy 0.9652 1.778)
			)
			(stroke
				(width 0)
				(type default)
			)
			(fill no)
			(layer "B.Fab")
		)
		(pad "1" smd rect
			(at 0 -0.9652)
			(size 1.397 1.143)
			(layers "B.Cu" "B.Mask" "B.Paste")
			(net "P3V3_M2")
		)
		(pad "2" smd rect
			(at 0 0.9652)
			(size 1.397 1.143)
			(layers "B.Cu" "B.Mask" "B.Paste")
			(net "GND")
		)
	)
	(footprint ""
		(layer "B.Cu")
		(at 10.174732 -136.716516 90)
		(property "Reference" "R250"
			(at 0 0 90)
			(layer "B.SilkS")
			(hide yes)
			(effects
				(font
					(size 1.27 1.27)
				)
				(justify mirror)
			)
		)
		(property "Value" "120R2F-GP"
			(at -0.064008 -3.993896 90)
			(unlocked yes)
			(layer "B.Fab")
			(hide yes)
			(effects
				(font
					(size 1.016 1.016)
					(thickness 0.1524)
				)
				(justify mirror)
			)
		)
		(property "Device Type" "R402H16"
			(at -0.064008 -5.517896 90)
			(unlocked yes)
			(layer "B.Fab")
			(hide yes)
			(effects
				(font
					(size 1.016 1.016)
					(thickness 0.1524)
				)
				(justify mirror)
			)
		)
		(duplicate_pad_numbers_are_jumpers no)
		(fp_line
			(start 0.508 -0.9398)
			(end 0.508 0.9398)
			(stroke
				(width 0.1524)
				(type default)
			)
			(layer "B.SilkS")
		)
		(fp_line
			(start -0.508 -0.9398)
			(end 0.508 -0.9398)
			(stroke
				(width 0.1524)
				(type default)
			)
			(layer "B.SilkS")
		)
		(fp_rect
			(start 0.508 0.9398)
			(end -0.508 -0.9398)
			(stroke
				(width 0)
				(type default)
			)
			(fill no)
			(layer "B.CrtYd")
		)
		(fp_rect
			(start 0.508 0.9398)
			(end -0.508 -0.9398)
			(stroke
				(width 0)
				(type default)
			)
			(fill no)
			(layer "B.Fab")
		)
		(pad "1" smd custom
			(at 0 -0.4445 270)
			(size 0.1397 0.1397)
			(layers "B.Cu" "B.Mask" "B.Paste")
			(net "GND")
			(options
				(clearance outline)
				(anchor circle)
			)
			(primitives
				(gr_poly
					(pts
						(arc
							(start -0.1778 0.2794)
							(mid -0.249642 0.249642)
							(end -0.2794 0.1778)
						)
						(arc
							(start -0.2794 -0.1778)
							(mid -0.249642 -0.249642)
							(end -0.1778 -0.2794)
						)
						(arc
							(start 0.1778 -0.2794)
							(mid 0.249642 -0.249642)
							(end 0.2794 -0.1778)
						)
						(arc
							(start 0.2794 0.1778)
							(mid 0.249642 0.249642)
							(end 0.1778 0.2794)
						)
					)
					(width 0)
					(fill yes)
				)
			)
		)
		(pad "2" smd custom
			(at 0 0.4445 270)
			(size 0.1397 0.1397)
			(layers "B.Cu" "B.Mask" "B.Paste")
			(net "MEMA_8")
			(options
				(clearance outline)
				(anchor circle)
			)
			(primitives
				(gr_poly
					(pts
						(arc
							(start -0.1778 0.2794)
							(mid -0.249642 0.249642)
							(end -0.2794 0.1778)
						)
						(arc
							(start -0.2794 -0.1778)
							(mid -0.249642 -0.249642)
							(end -0.1778 -0.2794)
						)
						(arc
							(start 0.1778 -0.2794)
							(mid 0.249642 -0.249642)
							(end 0.2794 -0.1778)
						)
						(arc
							(start 0.2794 0.1778)
							(mid 0.249642 0.249642)
							(end 0.1778 0.2794)
						)
					)
					(width 0)
					(fill yes)
				)
			)
		)
	)
	(footprint ""
		(layer "B.Cu")
		(at 10.20445 -133.85673 90)
		(property "Reference" "R242"
			(at 0 0 90)
			(layer "B.SilkS")
			(hide yes)
			(effects
				(font
					(size 1.27 1.27)
				)
				(justify mirror)
			)
		)
		(property "Value" "120R2F-GP"
			(at -0.064008 -3.993896 90)
			(unlocked yes)
			(layer "B.Fab")
			(hide yes)
			(effects
				(font
					(size 1.016 1.016)
					(thickness 0.1524)
				)
				(justify mirror)
			)
		)
		(property "Device Type" "R402H16"
			(at -0.064008 -5.517896 90)
			(unlocked yes)
			(layer "B.Fab")
			(hide yes)
			(effects
				(font
					(size 1.016 1.016)
					(thickness 0.1524)
				)
				(justify mirror)
			)
		)
		(duplicate_pad_numbers_are_jumpers no)
		(fp_line
			(start 0.508 -0.9398)
			(end 0.508 0.9398)
			(stroke
				(width 0.1524)
				(type default)
			)
			(layer "B.SilkS")
		)
		(fp_line
			(start -0.508 -0.9398)
			(end 0.508 -0.9398)
			(stroke
				(width 0.1524)
				(type default)
			)
			(layer "B.SilkS")
		)
		(fp_rect
			(start 0.508 0.9398)
			(end -0.508 -0.9398)
			(stroke
				(width 0)
				(type default)
			)
			(fill no)
			(layer "B.CrtYd")
		)
		(fp_rect
			(start 0.508 0.9398)
			(end -0.508 -0.9398)
			(stroke
				(width 0)
				(type default)
			)
			(fill no)
			(layer "B.Fab")
		)
		(pad "1" smd custom
			(at 0 -0.4445 270)
			(size 0.1397 0.1397)
			(layers "B.Cu" "B.Mask" "B.Paste")
			(net "GND")
			(options
				(clearance outline)
				(anchor circle)
			)
			(primitives
				(gr_poly
					(pts
						(arc
							(start -0.1778 0.2794)
							(mid -0.249642 0.249642)
							(end -0.2794 0.1778)
						)
						(arc
							(start -0.2794 -0.1778)
							(mid -0.249642 -0.249642)
							(end -0.1778 -0.2794)
						)
						(arc
							(start 0.1778 -0.2794)
							(mid 0.249642 -0.249642)
							(end 0.2794 -0.1778)
						)
						(arc
							(start 0.2794 0.1778)
							(mid 0.249642 0.249642)
							(end 0.1778 0.2794)
						)
					)
					(width 0)
					(fill yes)
				)
			)
		)
		(pad "2" smd custom
			(at 0 0.4445 270)
			(size 0.1397 0.1397)
			(layers "B.Cu" "B.Mask" "B.Paste")
			(net "MEMA_4")
			(options
				(clearance outline)
				(anchor circle)
			)
			(primitives
				(gr_poly
					(pts
						(arc
							(start -0.1778 0.2794)
							(mid -0.249642 0.249642)
							(end -0.2794 0.1778)
						)
						(arc
							(start -0.2794 -0.1778)
							(mid -0.249642 -0.249642)
							(end -0.1778 -0.2794)
						)
						(arc
							(start 0.1778 -0.2794)
							(mid 0.249642 -0.249642)
							(end 0.2794 -0.1778)
						)
						(arc
							(start 0.2794 0.1778)
							(mid 0.249642 0.249642)
							(end 0.1778 0.2794)
						)
					)
					(width 0)
					(fill yes)
				)
			)
		)
	)
	(footprint ""
		(layer "B.Cu")
		(at 12.11199 -141.008862 90)
		(property "Reference" "R255"
			(at 0 0 90)
			(layer "B.SilkS")
			(hide yes)
			(effects
				(font
					(size 1.27 1.27)
				)
				(justify mirror)
			)
		)
		(property "Value" "120R2F-GP"
			(at -0.064008 -3.993896 90)
			(unlocked yes)
			(layer "B.Fab")
			(hide yes)
			(effects
				(font
					(size 1.016 1.016)
					(thickness 0.1524)
				)
				(justify mirror)
			)
		)
		(property "Device Type" "R402H16"
			(at -0.064008 -5.517896 90)
			(unlocked yes)
			(layer "B.Fab")
			(hide yes)
			(effects
				(font
					(size 1.016 1.016)
					(thickness 0.1524)
				)
				(justify mirror)
			)
		)
		(duplicate_pad_numbers_are_jumpers no)
		(fp_line
			(start 0.508 -0.9398)
			(end 0.508 0.9398)
			(stroke
				(width 0.1524)
				(type default)
			)
			(layer "B.SilkS")
		)
		(fp_line
			(start -0.508 -0.9398)
			(end 0.508 -0.9398)
			(stroke
				(width 0.1524)
				(type default)
			)
			(layer "B.SilkS")
		)
		(fp_rect
			(start 0.508 0.9398)
			(end -0.508 -0.9398)
			(stroke
				(width 0)
				(type default)
			)
			(fill no)
			(layer "B.CrtYd")
		)
		(fp_rect
			(start 0.508 0.9398)
			(end -0.508 -0.9398)
			(stroke
				(width 0)
				(type default)
			)
			(fill no)
			(layer "B.Fab")
		)
		(pad "1" smd custom
			(at 0 -0.4445 270)
			(size 0.1397 0.1397)
			(layers "B.Cu" "B.Mask" "B.Paste")
			(net "MEMA_10")
			(options
				(clearance outline)
				(anchor circle)
			)
			(primitives
				(gr_poly
					(pts
						(arc
							(start -0.1778 0.2794)
							(mid -0.249642 0.249642)
							(end -0.2794 0.1778)
						)
						(arc
							(start -0.2794 -0.1778)
							(mid -0.249642 -0.249642)
							(end -0.1778 -0.2794)
						)
						(arc
							(start 0.1778 -0.2794)
							(mid 0.249642 -0.249642)
							(end 0.2794 -0.1778)
						)
						(arc
							(start 0.2794 0.1778)
							(mid 0.249642 0.249642)
							(end 0.1778 0.2794)
						)
					)
					(width 0)
					(fill yes)
				)
			)
		)
		(pad "2" smd custom
			(at 0 0.4445 270)
			(size 0.1397 0.1397)
			(layers "B.Cu" "B.Mask" "B.Paste")
			(net "P1V2_STBY")
			(options
				(clearance outline)
				(anchor circle)
			)
			(primitives
				(gr_poly
					(pts
						(arc
							(start -0.1778 0.2794)
							(mid -0.249642 0.249642)
							(end -0.2794 0.1778)
						)
						(arc
							(start -0.2794 -0.1778)
							(mid -0.249642 -0.249642)
							(end -0.1778 -0.2794)
						)
						(arc
							(start 0.1778 -0.2794)
							(mid 0.249642 -0.249642)
							(end 0.2794 -0.1778)
						)
						(arc
							(start 0.2794 0.1778)
							(mid 0.249642 0.249642)
							(end 0.1778 0.2794)
						)
					)
					(width 0)
					(fill yes)
				)
			)
		)
	)
	(footprint ""
		(layer "B.Cu")
		(at 25.334976 -141.03096 -90)
		(property "Reference" "R223"
			(at 0 0 90)
			(layer "B.SilkS")
			(hide yes)
			(effects
				(font
					(size 1.27 1.27)
				)
				(justify mirror)
			)
		)
		(property "Value" "120R2F-GP"
			(at -0.064008 -3.993896 270)
			(unlocked yes)
			(layer "B.Fab")
			(hide yes)
			(effects
				(font
					(size 1.016 1.016)
					(thickness 0.1524)
				)
				(justify mirror)
			)
		)
		(property "Device Type" "R402H16"
			(at -0.064008 -5.517896 270)
			(unlocked yes)
			(layer "B.Fab")
			(hide yes)
			(effects
				(font
					(size 1.016 1.016)
					(thickness 0.1524)
				)
				(justify mirror)
			)
		)
		(duplicate_pad_numbers_are_jumpers no)
		(fp_line
			(start -0.508 -0.9398)
			(end 0.508 -0.9398)
			(stroke
				(width 0.1524)
				(type default)
			)
			(layer "B.SilkS")
		)
		(fp_line
			(start 0.508 -0.9398)
			(end 0.508 0.9398)
			(stroke
				(width 0.1524)
				(type default)
			)
			(layer "B.SilkS")
		)
		(fp_rect
			(start 0.508 0.9398)
			(end -0.508 -0.9398)
			(stroke
				(width 0)
				(type default)
			)
			(fill no)
			(layer "B.CrtYd")
		)
		(fp_rect
			(start 0.508 0.9398)
			(end -0.508 -0.9398)
			(stroke
				(width 0)
				(type default)
			)
			(fill no)
			(layer "B.Fab")
		)
		(pad "1" smd custom
			(at 0 -0.4445 90)
			(size 0.1397 0.1397)
			(layers "B.Cu" "B.Mask" "B.Paste")
			(net "MEMRASN")
			(options
				(clearance outline)
				(anchor circle)
			)
			(primitives
				(gr_poly
					(pts
						(arc
							(start -0.1778 0.2794)
							(mid -0.249642 0.249642)
							(end -0.2794 0.1778)
						)
						(arc
							(start -0.2794 -0.1778)
							(mid -0.249642 -0.249642)
							(end -0.1778 -0.2794)
						)
						(arc
							(start 0.1778 -0.2794)
							(mid 0.249642 -0.249642)
							(end 0.2794 -0.1778)
						)
						(arc
							(start 0.2794 0.1778)
							(mid 0.249642 0.249642)
							(end 0.1778 0.2794)
						)
					)
					(width 0)
					(fill yes)
				)
			)
		)
		(pad "2" smd custom
			(at 0 0.4445 90)
			(size 0.1397 0.1397)
			(layers "B.Cu" "B.Mask" "B.Paste")
			(net "P1V2_STBY")
			(options
				(clearance outline)
				(anchor circle)
			)
			(primitives
				(gr_poly
					(pts
						(arc
							(start -0.1778 0.2794)
							(mid -0.249642 0.249642)
							(end -0.2794 0.1778)
						)
						(arc
							(start -0.2794 -0.1778)
							(mid -0.249642 -0.249642)
							(end -0.1778 -0.2794)
						)
						(arc
							(start 0.1778 -0.2794)
							(mid 0.249642 -0.249642)
							(end 0.2794 -0.1778)
						)
						(arc
							(start 0.2794 0.1778)
							(mid 0.249642 0.249642)
							(end 0.1778 0.2794)
						)
					)
					(width 0)
					(fill yes)
				)
			)
		)
	)
	(footprint ""
		(layer "B.Cu")
		(at 46.65218 -134.636764 180)
		(property "Reference" "R152"
			(at 0 0 0)
			(layer "B.SilkS")
			(hide yes)
			(effects
				(font
					(size 1.27 1.27)
				)
				(justify mirror)
			)
		)
		(property "Value" "0R2J-2-GP"
			(at -0.064008 -3.993896 180)
			(unlocked yes)
			(layer "B.Fab")
			(hide yes)
			(effects
				(font
					(size 1.016 1.016)
					(thickness 0.1524)
				)
				(justify mirror)
			)
		)
		(property "Device Type" "R402H16"
			(at -0.064008 -5.517896 180)
			(unlocked yes)
			(layer "B.Fab")
			(hide yes)
			(effects
				(font
					(size 1.016 1.016)
					(thickness 0.1524)
				)
				(justify mirror)
			)
		)
		(duplicate_pad_numbers_are_jumpers no)
		(fp_line
			(start 0.508 -0.9398)
			(end 0.508 0.9398)
			(stroke
				(width 0.1524)
				(type default)
			)
			(layer "B.SilkS")
		)
		(fp_line
			(start -0.508 -0.9398)
			(end 0.508 -0.9398)
			(stroke
				(width 0.1524)
				(type default)
			)
			(layer "B.SilkS")
		)
		(fp_rect
			(start 0.508 0.9398)
			(end -0.508 -0.9398)
			(stroke
				(width 0)
				(type default)
			)
			(fill no)
			(layer "B.CrtYd")
		)
		(fp_rect
			(start 0.508 0.9398)
			(end -0.508 -0.9398)
			(stroke
				(width 0)
				(type default)
			)
			(fill no)
			(layer "B.Fab")
		)
		(pad "1" smd custom
			(at 0 -0.4445)
			(size 0.1397 0.1397)
			(layers "B.Cu" "B.Mask" "B.Paste")
			(net "I2C_IOM_SCL")
			(options
				(clearance outline)
				(anchor circle)
			)
			(primitives
				(gr_poly
					(pts
						(arc
							(start -0.1778 0.2794)
							(mid -0.249642 0.249642)
							(end -0.2794 0.1778)
						)
						(arc
							(start -0.2794 -0.1778)
							(mid -0.249642 -0.249642)
							(end -0.1778 -0.2794)
						)
						(arc
							(start 0.1778 -0.2794)
							(mid 0.249642 -0.249642)
							(end 0.2794 -0.1778)
						)
						(arc
							(start 0.2794 0.1778)
							(mid 0.249642 0.249642)
							(end 0.1778 0.2794)
						)
					)
					(width 0)
					(fill yes)
				)
			)
		)
		(pad "2" smd custom
			(at 0 0.4445)
			(size 0.1397 0.1397)
			(layers "B.Cu" "B.Mask" "B.Paste")
			(net "BMC_SMB1_CLK")
			(options
				(clearance outline)
				(anchor circle)
			)
			(primitives
				(gr_poly
					(pts
						(arc
							(start -0.1778 0.2794)
							(mid -0.249642 0.249642)
							(end -0.2794 0.1778)
						)
						(arc
							(start -0.2794 -0.1778)
							(mid -0.249642 -0.249642)
							(end -0.1778 -0.2794)
						)
						(arc
							(start 0.1778 -0.2794)
							(mid 0.249642 -0.249642)
							(end 0.2794 -0.1778)
						)
						(arc
							(start 0.2794 0.1778)
							(mid 0.249642 0.249642)
							(end 0.1778 0.2794)
						)
					)
					(width 0)
					(fill yes)
				)
			)
		)
	)
	(footprint ""
		(layer "B.Cu")
		(at 219.82303 -53.89499 -90)
		(property "Reference" "C157"
			(at 0 0 90)
			(layer "B.SilkS")
			(hide yes)
			(effects
				(font
					(size 1.27 1.27)
				)
				(justify mirror)
			)
		)
		(property "Value" "SC4D7U25V5KX-1-GP"
			(at 0.0762 -6.1214 270)
			(unlocked yes)
			(layer "B.Fab")
			(hide yes)
			(effects
				(font
					(size 1.016 1.016)
					(thickness 0.1524)
				)
				(justify mirror)
			)
		)
		(property "Device Type" "C805H58"
			(at 0.0762 -8.1534 270)
			(unlocked yes)
			(layer "B.Fab")
			(hide yes)
			(effects
				(font
					(size 1.016 1.016)
					(thickness 0.1524)
				)
				(justify mirror)
			)
		)
		(duplicate_pad_numbers_are_jumpers no)
		(fp_line
			(start -0.635 0)
			(end 0.635 0)
			(stroke
				(width 0.508)
				(type default)
			)
			(layer "B.SilkS")
		)
		(fp_rect
			(start 0.9652 1.778)
			(end -0.9652 -1.778)
			(stroke
				(width 0)
				(type default)
			)
			(fill no)
			(layer "B.CrtYd")
		)
		(fp_poly
			(pts
				(xy 0.9652 -1.778) (xy -0.9652 -1.778) (xy -0.9652 1.778) (xy 0.9652 1.778)
			)
			(stroke
				(width 0)
				(type default)
			)
			(fill no)
			(layer "B.Fab")
		)
		(pad "1" smd rect
			(at 0 -0.9652 90)
			(size 1.397 1.143)
			(layers "B.Cu" "B.Mask" "B.Paste")
			(net "P5V_VDD")
		)
		(pad "2" smd rect
			(at 0 0.9652 90)
			(size 1.397 1.143)
			(layers "B.Cu" "B.Mask" "B.Paste")
			(net "GND")
		)
	)
)
